# TIMECARD (Time Appliance Project (Time Card)) — schematic netlist excerpt (pin names and nets, part order shuffled) for the footprints in the layout excerpt that follows; sources: Cadence DE-HDL packaged netlist, KiCad conversion of R4006-B0001-02_R01.brd

R306  RESISTOR  4.7KOHM 1%  pkg SMC_0402R_H016  page 20 : \1\ = XP3R3V_FPGA ; \2\ = UNNAMED_9_BNO080LGA28_I29_CLKSE
TP133  TP_PIONT  pkg TP010CT020B030_PTH  page 25 : \1\ = IO_L20N_34
R7  RESISTOR  0OHM -  pkg SMC_0402R_H016  page 27 : \1\ = SG ; \2\ = UNNAMED_15_MP5022CGQVZQFN22_I_2
SP71  NULL  pkg DUMMY  page 34

(kicad_pcb
	(version 20260206)
	(generator "pcbnew")
	(generator_version "10.0")
	(general
		(thickness 1.6)
		(legacy_teardrops no)
	)
	(paper "A4")
	(title_block
		(title "timecard-production-celestica-r4006 — R4006-B0001-02_R01.brd")
		(comment 1 "Time Appliance Project (Time Card) / footprints 70-73 of 1113")
	)
	(layers
		(0 "F.Cu" signal "TOP")
		(4 "In1.Cu" signal "L02_GND1")
		(6 "In2.Cu" signal "L03_SIG1")
		(8 "In3.Cu" signal "L04_GND2")
		(10 "In4.Cu" signal "L05_VCC1")
		(12 "In5.Cu" signal "L06_VCC2")
		(14 "In6.Cu" signal "L07_GND3")
		(16 "In7.Cu" signal "L08_SIG2")
		(18 "In8.Cu" signal "L09_GND4")
		(2 "B.Cu" signal "BOTTOM")
		(9 "F.Adhes" user "F.Adhesive")
		(11 "B.Adhes" user "B.Adhesive")
		(13 "F.Paste" user "Package Geometry/Pastemask Top")
		(15 "B.Paste" user "Package Geometry/Pastemask Bottom")
		(5 "F.SilkS" user "Ref Des/Silkscreen Top")
		(7 "B.SilkS" user "Ref Des/Silkscreen Bottom")
		(1 "F.Mask" user "Board Geometry/Soldermask Top")
		(3 "B.Mask" user "Board Geometry/Soldermask Bottom")
		(17 "Dwgs.User" user "User.Drawings")
		(19 "Cmts.User" user "User.Comments")
		(21 "Eco1.User" user "User.Eco1")
		(23 "Eco2.User" user "User.Eco2")
		(25 "Edge.Cuts" user "Board Geometry/Outline")
		(27 "Margin" user)
		(31 "F.CrtYd" user "Package Geometry/Place Bound Top")
		(29 "B.CrtYd" user "Package Geometry/Place Bound Bottom")
		(35 "F.Fab" user "Ref Des/Assembly Top")
		(33 "B.Fab" user "Ref Des/Assembly Bottom")
	)
	(footprint ""
		(layer "F.Cu")
		(at 80.772 -61.8236)
		(property "Reference" "R306"
			(at -10.287 -19.51863 0)
			(unlocked yes)
			(layer "F.SilkS")
			(effects
				(font
					(size 0.7874 0.5842)
					(thickness 0.1524)
				)
			)
		)
		(property "Value" "VAL*"
			(at 0.02032 2.13233 0)
			(unlocked yes)
			(layer "F.Fab")
			(hide yes)
			(effects
				(font
					(size 0.7874 0.5842)
					(thickness 0.1524)
				)
			)
		)
		(property "Tolerance" "TOL*"
			(at 0.044704 3.05435 0)
			(unlocked yes)
			(layer "Cmts.User")
			(hide yes)
			(effects
				(font
					(size 0.7874 0.5842)
					(thickness 0.1524)
				)
			)
		)
		(property "User Part Number" "PARTNUM*"
			(at 0.02032 4.024884 0)
			(unlocked yes)
			(layer "Cmts.User")
			(hide yes)
			(effects
				(font
					(size 0.7874 0.5842)
					(thickness 0.1524)
				)
			)
		)
		(property "Device Type" "RESISTOR-G155-14701-01,4.7KOHMA"
			(at 0.008382 1.210564 0)
			(unlocked yes)
			(layer "F.Fab")
			(hide yes)
			(effects
				(font
					(size 0.7874 0.5842)
					(thickness 0.1524)
				)
			)
		)
		(duplicate_pad_numbers_are_jumpers no)
		(fp_line
			(start -1.143 -0.5588)
			(end -1.143 0.5588)
			(stroke
				(width 0.1)
				(type default)
			)
			(layer "F.SilkS")
		)
		(fp_line
			(start -1.143 0.5588)
			(end 1.143 0.5588)
			(stroke
				(width 0.1)
				(type default)
			)
			(layer "F.SilkS")
		)
		(fp_line
			(start 1.143 -0.5588)
			(end -1.143 -0.5588)
			(stroke
				(width 0.1)
				(type default)
			)
			(layer "F.SilkS")
		)
		(fp_line
			(start 1.143 0.5588)
			(end 1.143 -0.5588)
			(stroke
				(width 0.1)
				(type default)
			)
			(layer "F.SilkS")
		)
		(fp_rect
			(start -1.143 0.5588)
			(end 1.143 -0.5588)
			(stroke
				(width 0)
				(type default)
			)
			(fill no)
			(layer "F.CrtYd")
		)
		(fp_line
			(start -0.508 -0.3048)
			(end -0.508 0.3048)
			(stroke
				(width 0.1)
				(type default)
			)
			(layer "F.Fab")
		)
		(fp_line
			(start -0.508 0.3048)
			(end 0.508 0.3048)
			(stroke
				(width 0.1)
				(type default)
			)
			(layer "F.Fab")
		)
		(fp_line
			(start 0.508 -0.3048)
			(end -0.508 -0.3048)
			(stroke
				(width 0.1)
				(type default)
			)
			(layer "F.Fab")
		)
		(fp_line
			(start 0.508 0.3048)
			(end 0.508 -0.3048)
			(stroke
				(width 0.1)
				(type default)
			)
			(layer "F.Fab")
		)
		(pad "1" smd rect
			(at -0.5334 0)
			(size 0.7112 0.6096)
			(layers "F.Cu" "F.Mask" "F.Paste")
			(net "XP3R3V_FPGA")
		)
		(pad "2" smd rect
			(at 0.5334 0)
			(size 0.7112 0.6096)
			(layers "F.Cu" "F.Mask" "F.Paste")
			(net "UNNAMED_9_BNO080LGA28_I29_CLKSE")
		)
		(zone
			(layer "F.Cu")
			(hatch none 0.5)
			(connect_pads
				(clearance 0)
			)
			(min_thickness 0.25)
			(keepout
				(tracks allowed)
				(vias not_allowed)
				(pads allowed)
				(copperpour not_allowed)
				(footprints allowed)
			)
			(placement
				(enabled no)
				(sheetname "")
			)
			(fill
				(thermal_gap 0.5)
				(thermal_bridge_width 0.5)
				(island_removal_mode 0)
			)
			(polygon
				(pts
					(xy 80.6958 -61.5188) (xy 80.8482 -61.5188) (xy 80.8482 -62.1284) (xy 80.6958 -62.1284)
				)
			)
		)
	)
	(footprint ""
		(layer "F.Cu")
		(at 55.88 -131.572)
		(property "Reference" "SP71"
			(at 0 0 0)
			(layer "F.SilkS")
			(hide yes)
			(effects
				(font
					(size 1.27 1.27)
				)
			)
		)
		(property "Value" ""
			(at 0 0 0)
			(layer "F.Fab")
			(effects
				(font
					(size 1.27 1.27)
				)
			)
		)
		(duplicate_pad_numbers_are_jumpers no)
	)
	(footprint ""
		(layer "F.Cu")
		(at 120.346978 -38.323266)
		(property "Reference" "TP133"
			(at 0 0 0)
			(layer "F.SilkS")
			(hide yes)
			(effects
				(font
					(size 1.27 1.27)
				)
			)
		)
		(property "Value" ""
			(at 0 0 0)
			(layer "F.Fab")
			(effects
				(font
					(size 1.27 1.27)
				)
			)
		)
		(property "Device Type" "TP_PIONT-TP010CT020B030_PTH-TPA"
			(at -1.341882 0.996696 0)
			(unlocked yes)
			(layer "F.Fab")
			(hide yes)
			(effects
				(font
					(size 0.7874 0.5842)
					(thickness 0.1524)
				)
				(justify left)
			)
		)
		(duplicate_pad_numbers_are_jumpers no)
		(fp_poly
			(pts
				(arc
					(start 0.889 0)
					(mid -0.889 0)
					(end 0.889 0)
				)
			)
			(stroke
				(width 0)
				(type default)
			)
			(fill no)
			(layer "B.CrtYd")
		)
		(fp_poly
			(pts
				(arc
					(start 0.889 0)
					(mid -0.889 0)
					(end 0.889 0)
				)
			)
			(stroke
				(width 0)
				(type default)
			)
			(fill no)
			(layer "F.CrtYd")
		)
		(pad "1" thru_hole circle
			(at 0 0)
			(size 0.508 0.508)
			(drill 0.254)
			(layers "*.Cu" "*.Mask")
			(remove_unused_layers no)
			(net "IO_L20N_34")
			(clearance 0.1016)
			(padstack
				(mode front_inner_back)
				(layer "Inner"
					(shape circle)
					(size 0.508 0.508)
					(clearance 0.1016)
				)
				(layer "B.Cu"
					(shape circle)
					(size 0.762 0.762)
					(clearance -0.0254)
				)
			)
		)
	)
	(footprint ""
		(layer "F.Cu")
		(at 145.8214 -91.8718 180)
		(property "Reference" "R7"
			(at 0.2794 -8.47217 0)
			(unlocked yes)
			(layer "F.SilkS")
			(effects
				(font
					(size 0.7874 0.5842)
					(thickness 0.1524)
				)
			)
		)
		(property "Value" "VAL*"
			(at 0.02032 2.13233 180)
			(unlocked yes)
			(layer "F.Fab")
			(hide yes)
			(effects
				(font
					(size 0.7874 0.5842)
					(thickness 0.1524)
				)
			)
		)
		(property "Device Type" "RESISTOR-G155-100R0-J0,0OHM,-"
			(at 0.008382 1.210564 180)
			(unlocked yes)
			(layer "F.Fab")
			(hide yes)
			(effects
				(font
					(size 0.7874 0.5842)
					(thickness 0.1524)
				)
			)
		)
		(property "User Part Number" "PARTNUM*"
			(at 0.02032 4.024884 180)
			(unlocked yes)
			(layer "Cmts.User")
			(hide yes)
			(effects
				(font
					(size 0.7874 0.5842)
					(thickness 0.1524)
				)
			)
		)
		(property "Tolerance" "TOL*"
			(at 0.044704 3.05435 180)
			(unlocked yes)
			(layer "Cmts.User")
			(hide yes)
			(effects
				(font
					(size 0.7874 0.5842)
					(thickness 0.1524)
				)
			)
		)
		(duplicate_pad_numbers_are_jumpers no)
		(fp_line
			(start 1.143 0.5588)
			(end 1.143 -0.5588)
			(stroke
				(width 0.1)
				(type default)
			)
			(layer "F.SilkS")
		)
		(fp_line
			(start 1.143 -0.5588)
			(end -1.143 -0.5588)
			(stroke
				(width 0.1)
				(type default)
			)
			(layer "F.SilkS")
		)
		(fp_line
			(start -1.143 0.5588)
			(end 1.143 0.5588)
			(stroke
				(width 0.1)
				(type default)
			)
			(layer "F.SilkS")
		)
		(fp_line
			(start -1.143 -0.5588)
			(end -1.143 0.5588)
			(stroke
				(width 0.1)
				(type default)
			)
			(layer "F.SilkS")
		)
		(fp_rect
			(start 1.143 -0.5588)
			(end -1.143 0.5588)
			(stroke
				(width 0)
				(type default)
			)
			(fill no)
			(layer "F.CrtYd")
		)
		(fp_line
			(start 0.508 0.3048)
			(end 0.508 -0.3048)
			(stroke
				(width 0.1)
				(type default)
			)
			(layer "F.Fab")
		)
		(fp_line
			(start 0.508 -0.3048)
			(end -0.508 -0.3048)
			(stroke
				(width 0.1)
				(type default)
			)
			(layer "F.Fab")
		)
		(fp_line
			(start -0.508 0.3048)
			(end 0.508 0.3048)
			(stroke
				(width 0.1)
				(type default)
			)
			(layer "F.Fab")
		)
		(fp_line
			(start -0.508 -0.3048)
			(end -0.508 0.3048)
			(stroke
				(width 0.1)
				(type default)
			)
			(layer "F.Fab")
		)
		(pad "1" smd rect
			(at -0.5334 0 180)
			(size 0.7112 0.6096)
			(layers "F.Cu" "F.Mask" "F.Paste")
			(net "SG")
		)
		(pad "2" smd rect
			(at 0.5334 0 180)
			(size 0.7112 0.6096)
			(layers "F.Cu" "F.Mask" "F.Paste")
			(net "UNNAMED_15_MP5022CGQVZQFN22_I_2")
		)
		(zone
			(layer "F.Cu")
			(hatch none 0.5)
			(connect_pads
				(clearance 0)
			)
			(min_thickness 0.25)
			(keepout
				(tracks allowed)
				(vias not_allowed)
				(pads allowed)
				(copperpour not_allowed)
				(footprints allowed)
			)
			(placement
				(enabled no)
				(sheetname "")
			)
			(fill
				(thermal_gap 0.5)
				(thermal_bridge_width 0.5)
				(island_removal_mode 0)
			)
			(polygon
				(pts
					(xy 145.7452 -91.567) (xy 145.8976 -91.567) (xy 145.8976 -92.1766) (xy 145.7452 -92.1766)
				)
			)
		)
	)
)
